(kicad_pcb
	(version 20241229)
	(generator "pcbnew")
	(generator_version "9.0")
	(general
		(thickness 1.63)
		(legacy_teardrops no)
	)
	(paper "A4")
	(title_block
		(title "CM4 Baseboard")
		(date "2026-01-05")
		(rev "1.1.1")
		(company "Antmicro Ltd")
		(comment 1 "www.antmicro.com")
		(comment 9 "footprints 321-324 of 506")
	)
	(layers
		(0 "F.Cu" signal)
		(4 "In1.Cu" power)
		(6 "In2.Cu" power)
		(8 "In3.Cu" signal)
		(10 "In4.Cu" signal)
		(2 "B.Cu" signal)
		(9 "F.Adhes" user "F.Adhesive")
		(11 "B.Adhes" user "B.Adhesive")
		(13 "F.Paste" user)
		(15 "B.Paste" user)
		(5 "F.SilkS" user "F.Silkscreen")
		(7 "B.SilkS" user "B.Silkscreen")
		(1 "F.Mask" user)
		(3 "B.Mask" user)
		(17 "Dwgs.User" user "User.Drawings")
		(19 "Cmts.User" user "User.Comments")
		(21 "Eco1.User" user "User.Eco1")
		(23 "Eco2.User" user "User.Eco2")
		(25 "Edge.Cuts" user)
		(27 "Margin" user)
		(31 "F.CrtYd" user "F.Courtyard")
		(29 "B.CrtYd" user "B.Courtyard")
		(35 "F.Fab" user)
		(33 "B.Fab" user)
	)
	(footprint "antmicro-footprints:LED_0603_1608Metric_G"
		(layer "F.Cu")
		(at 88.992962 120.9915 180)
		(descr "LED SMD 0603 Green")
		(tags "LED SMD 0603 Green")
		(property "Reference" "D905"
			(at -0.175 0.525 0)
			(layer "F.SilkS")
			(effects
				(font
					(size 0.7 0.7)
					(thickness 0.15)
				)
				(justify right bottom)
			)
		)
		(property "Value" "LED_G_0603_KP-1608CGCK"
			(at -0.001 1.599 0)
			(layer "F.Fab")
			(effects
				(font
					(size 0.7 0.7)
					(thickness 0.15)
				)
				(justify right bottom)
			)
		)
		(property "Datasheet" "http://www.kingbright.com/attachments/file/psearch//000/00/00/KP-1608CGCK(Ver.23B).pdf"
			(at 0 0 180)
			(layer "F.Fab")
			(hide yes)
			(effects
				(font
					(size 1.27 1.27)
					(thickness 0.15)
				)
			)
		)
		(property "MPN" "KP-1608CGCK"
			(at 0 0 180)
			(unlocked yes)
			(layer "F.Fab")
			(hide yes)
			(effects
				(font
					(size 1 1)
					(thickness 0.15)
				)
			)
		)
		(property "Manufacturer" "Kingbright"
			(at 0 0 180)
			(unlocked yes)
			(layer "F.Fab")
			(hide yes)
			(effects
				(font
					(size 1 1)
					(thickness 0.15)
				)
			)
		)
		(property "Color" "Green"
			(at 0 0 180)
			(unlocked yes)
			(layer "F.Fab")
			(hide yes)
			(effects
				(font
					(size 1 1)
					(thickness 0.15)
				)
			)
		)
		(property "Author" "Antmicro"
			(at 0 0 180)
			(unlocked yes)
			(layer "F.Fab")
			(hide yes)
			(effects
				(font
					(size 1 1)
					(thickness 0.15)
				)
			)
		)
		(property "License" "Apache-2.0"
			(at 0 0 180)
			(unlocked yes)
			(layer "F.Fab")
			(hide yes)
			(effects
				(font
					(size 1 1)
					(thickness 0.15)
				)
			)
		)
		(sheetname "/USB/")
		(sheetfile "usb.kicad_sch")
		(attr smd)
		(fp_line
			(start 0.22 0.35)
			(end -0.22 0.35)
			(stroke
				(width 0.15)
				(type solid)
			)
			(layer "F.SilkS")
		)
		(fp_line
			(start 0.22 -0.35)
			(end -0.22 -0.35)
			(stroke
				(width 0.15)
				(type solid)
			)
			(layer "F.SilkS")
		)
		(fp_line
			(start 0.105328 0.201008)
			(end 0.105328 -0.198992)
			(stroke
				(width 0.1)
				(type solid)
			)
			(layer "F.SilkS")
		)
		(fp_line
			(start 0.105328 0.201008)
			(end -0.094672 0.001008)
			(stroke
				(width 0.1)
				(type solid)
			)
			(layer "F.SilkS")
		)
		(fp_line
			(start 0.105328 0.001008)
			(end 0.24 0.001)
			(stroke
				(width 0.1)
				(type solid)
			)
			(layer "F.SilkS")
		)
		(fp_line
			(start -0.094672 0.201008)
			(end -0.094672 -0.198992)
			(stroke
				(width 0.1)
				(type solid)
			)
			(layer "F.SilkS")
		)
		(fp_line
			(start -0.094672 0.001008)
			(end 0.105328 -0.198992)
			(stroke
				(width 0.1)
				(type solid)
			)
			(layer "F.SilkS")
		)
		(fp_line
			(start -0.094672 0.001008)
			(end -0.24 0.001008)
			(stroke
				(width 0.1)
				(type solid)
			)
			(layer "F.SilkS")
		)
		(fp_line
			(start -1.18 -0.319)
			(end -1.18 0.321)
			(stroke
				(width 0.15)
				(type solid)
			)
			(layer "F.SilkS")
		)
		(fp_rect
			(start 1.25 0.65)
			(end -1.25 -0.65)
			(stroke
				(width 0.05)
				(type solid)
			)
			(fill no)
			(layer "F.CrtYd")
		)
		(fp_line
			(start 0.599 0)
			(end 0.201 0)
			(stroke
				(width 0.15)
				(type solid)
			)
			(layer "F.Fab")
		)
		(fp_line
			(start 0.201 0.2)
			(end 0.201 0)
			(stroke
				(width 0.15)
				(type solid)
			)
			(layer "F.Fab")
		)
		(fp_line
			(start 0.201 0)
			(end 0.201 -0.202)
			(stroke
				(width 0.15)
				(type solid)
			)
			(layer "F.Fab")
		)
		(fp_line
			(start 0.201 -0.202)
			(end -0.101 0)
			(stroke
				(width 0.15)
				(type solid)
			)
			(layer "F.Fab")
		)
		(fp_line
			(start -0.101 0)
			(end 0.201 0.2)
			(stroke
				(width 0.15)
				(type solid)
			)
			(layer "F.Fab")
		)
		(fp_line
			(start -0.199 0.2)
			(end -0.199 0.1)
			(stroke
				(width 0.15)
				(type solid)
			)
			(layer "F.Fab")
		)
		(fp_line
			(start -0.199 0)
			(end -0.597 0)
			(stroke
				(width 0.15)
				(type solid)
			)
			(layer "F.Fab")
		)
		(fp_line
			(start -0.199 -0.202)
			(end -0.199 0.1)
			(stroke
				(width 0.15)
				(type solid)
			)
			(layer "F.Fab")
		)
		(fp_rect
			(start 0.848 0.4)
			(end -0.85 -0.402)
			(stroke
				(width 0.15)
				(type solid)
			)
			(fill no)
			(layer "F.Fab")
		)
		(fp_text user "Author: Antmicro"
			(at -1.4224 4.799 180)
			(layer "F.Fab")
			(effects
				(font
					(size 0.7 0.7)
					(thickness 0.15)
				)
				(justify left bottom)
			)
		)
		(fp_text user "License: Apache-2.0"
			(at -1.4224 3.599 180)
			(layer "F.Fab")
			(effects
				(font
					(size 0.7 0.7)
					(thickness 0.15)
				)
				(justify left bottom)
			)
		)
		(fp_text user "${REFERENCE}"
			(at -1.4224 5.999 180)
			(layer "F.Fab")
			(effects
				(font
					(size 0.7 0.7)
					(thickness 0.15)
				)
				(justify left bottom)
			)
		)
		(pad "1" smd roundrect
			(at -0.7 0)
			(size 0.8 1)
			(layers "F.Cu" "F.Mask" "F.Paste")
			(roundrect_rratio 0.2)
			(net 3 "GND")
			(pinfunction "C")
			(pintype "passive")
		)
		(pad "2" smd roundrect
			(at 0.7 0)
			(size 0.8 1)
			(layers "F.Cu" "F.Mask" "F.Paste")
			(roundrect_rratio 0.2)
			(net 482 "Net-(D905-A)")
			(pinfunction "A")
			(pintype "passive")
		)
	)
	(footprint "antmicro-footprints:R_0402_1005Metric"
		(layer "F.Cu")
		(at 92.817962 156.7665 180)
		(descr "Resistor SMD 0402")
		(tags "resistor SMD 0402")
		(property "Reference" "R234"
			(at -3.86 -0.6 0)
			(layer "F.SilkS")
			(effects
				(font
					(size 0.7 0.7)
					(thickness 0.15)
				)
				(justify right bottom)
			)
		)
		(property "Value" "R_10k_0402"
			(at -1.011843 1.772047 0)
			(layer "F.Fab")
			(effects
				(font
					(size 0.7 0.7)
					(thickness 0.15)
				)
				(justify right bottom)
			)
		)
		(property "Datasheet" "https://www.bourns.com/docs/product-datasheets/cr.pdf"
			(at 0 0 180)
			(layer "F.Fab")
			(hide yes)
			(effects
				(font
					(size 1.27 1.27)
					(thickness 0.15)
				)
			)
		)
		(property "MPN" "CR0402-FX-1002GLF"
			(at 0 0 180)
			(unlocked yes)
			(layer "F.Fab")
			(hide yes)
			(effects
				(font
					(size 1 1)
					(thickness 0.15)
				)
			)
		)
		(property "Manufacturer" "Bourns"
			(at 0 0 180)
			(unlocked yes)
			(layer "F.Fab")
			(hide yes)
			(effects
				(font
					(size 1 1)
					(thickness 0.15)
				)
			)
		)
		(property "License" "Apache-2.0"
			(at 0 0 180)
			(unlocked yes)
			(layer "F.Fab")
			(hide yes)
			(effects
				(font
					(size 1 1)
					(thickness 0.15)
				)
			)
		)
		(property "Author" "Antmicro"
			(at 0 0 180)
			(unlocked yes)
			(layer "F.Fab")
			(hide yes)
			(effects
				(font
					(size 1 1)
					(thickness 0.15)
				)
			)
		)
		(property "Val" "10k"
			(at 0 0 180)
			(unlocked yes)
			(layer "F.Fab")
			(hide yes)
			(effects
				(font
					(size 1 1)
					(thickness 0.15)
				)
			)
		)
		(property "Tolerance" "1%"
			(at 0 0 180)
			(unlocked yes)
			(layer "F.Fab")
			(hide yes)
			(effects
				(font
					(size 1 1)
					(thickness 0.15)
				)
			)
		)
		(sheetname "/Compute module/")
		(sheetfile "compute-module.kicad_sch")
		(attr smd)
		(fp_rect
			(start -0.925 -0.47)
			(end 0.925 0.47)
			(stroke
				(width 0.05)
				(type default)
			)
			(fill no)
			(layer "F.CrtYd")
		)
		(fp_rect
			(start -0.5 -0.25)
			(end 0.5 0.25)
			(stroke
				(width 0.15)
				(type solid)
			)
			(fill no)
			(layer "F.Fab")
		)
		(fp_text user "Author: Antmicro"
			(at -0.95 4.169 180)
			(layer "F.Fab")
			(effects
				(font
					(size 0.7 0.7)
					(thickness 0.15)
				)
				(justify left bottom)
			)
		)
		(fp_text user "License: Apache-2.0"
			(at -0.95 5.169 180)
			(layer "F.Fab")
			(effects
				(font
					(size 0.7 0.7)
					(thickness 0.15)
				)
				(justify left bottom)
			)
		)
		(fp_text user "${REFERENCE}"
			(at -0.95 3.168 180)
			(layer "F.Fab")
			(effects
				(font
					(size 0.7 0.7)
					(thickness 0.15)
				)
				(justify left bottom)
			)
		)
		(pad "1" smd roundrect
			(at -0.48 0 180)
			(size 0.59 0.64)
			(layers "F.Cu" "F.Mask" "F.Paste")
			(roundrect_rratio 0.25)
			(net 347 "/Compute module/ExpanderINT")
			(pintype "passive")
		)
		(pad "2" smd roundrect
			(at 0.48 0 180)
			(size 0.59 0.64)
			(layers "F.Cu" "F.Mask" "F.Paste")
			(roundrect_rratio 0.25)
			(net 9 "+3V3")
			(pintype "passive")
		)
	)
	(footprint "antmicro-footprints:Nexperia_DFN-10_2.5x1mm_P0.5mm"
		(layer "F.Cu")
		(at 92.767962 121.309429)
		(property "Reference" "D901"
			(at -1.18 -0.702929 0)
			(layer "F.SilkS")
			(effects
				(font
					(size 0.7 0.7)
					(thickness 0.15)
				)
				(justify left bottom)
			)
		)
		(property "Value" "PUSB3F96X_PASS"
			(at -0.016 1.705 0)
			(layer "F.Fab")
			(effects
				(font
					(size 0.7 0.7)
					(thickness 0.15)
				)
				(justify left bottom)
			)
		)
		(property "Datasheet" "https://mouser.com/datasheet/2/916/PUSB3F96-1600324.pdf"
			(at 0 0 0)
			(layer "F.Fab")
			(hide yes)
			(effects
				(font
					(size 1.27 1.27)
					(thickness 0.15)
				)
			)
		)
		(property "Manufacturer" "Nexperia"
			(at 0 0 0)
			(unlocked yes)
			(layer "F.Fab")
			(hide yes)
			(effects
				(font
					(size 1 1)
					(thickness 0.15)
				)
			)
		)
		(property "MPN" "PUSB3F96X"
			(at 0 0 0)
			(unlocked yes)
			(layer "F.Fab")
			(hide yes)
			(effects
				(font
					(size 1 1)
					(thickness 0.15)
				)
			)
		)
		(property "Author" "Antmicro"
			(at 0 0 0)
			(unlocked yes)
			(layer "F.Fab")
			(hide yes)
			(effects
				(font
					(size 1 1)
					(thickness 0.15)
				)
			)
		)
		(property "License" "Apache-2.0"
			(at 0 0 0)
			(unlocked yes)
			(layer "F.Fab")
			(hide yes)
			(effects
				(font
					(size 1 1)
					(thickness 0.15)
				)
			)
		)
		(sheetname "/USB/")
		(sheetfile "usb.kicad_sch")
		(attr smd)
		(fp_line
			(start -1.375 -0.4)
			(end -1.375 0.4)
			(stroke
				(width 0.15)
				(type solid)
			)
			(layer "F.SilkS")
		)
		(fp_line
			(start 1.375 0.4)
			(end 1.375 -0.4)
			(stroke
				(width 0.15)
				(type solid)
			)
			(layer "F.SilkS")
		)
		(fp_circle
			(center -1.4 0.7)
			(end -1.349 0.7)
			(stroke
				(width 0.15)
				(type solid)
			)
			(fill yes)
			(layer "F.SilkS")
		)
		(fp_rect
			(start -1.4 -0.725)
			(end 1.4 0.725)
			(stroke
				(width 0.05)
				(type solid)
			)
			(fill no)
			(layer "F.CrtYd")
		)
		(fp_line
			(start -1.25 -0.5)
			(end -1.25 0.15)
			(stroke
				(width 0.15)
				(type solid)
			)
			(layer "F.Fab")
		)
		(fp_line
			(start -1.25 0.15)
			(end -0.9 0.5)
			(stroke
				(width 0.15)
				(type solid)
			)
			(layer "F.Fab")
		)
		(fp_line
			(start -0.9 0.5)
			(end 1.25 0.5)
			(stroke
				(width 0.15)
				(type solid)
			)
			(layer "F.Fab")
		)
		(fp_line
			(start 1.25 -0.5)
			(end -1.25 -0.5)
			(stroke
				(width 0.15)
				(type solid)
			)
			(layer "F.Fab")
		)
		(fp_line
			(start 1.25 0.5)
			(end 1.25 -0.5)
			(stroke
				(width 0.15)
				(type solid)
			)
			(layer "F.Fab")
		)
		(fp_text user "${REFERENCE}"
			(at -1.367 3.704 0)
			(layer "F.Fab")
			(effects
				(font
					(size 0.7 0.7)
					(thickness 0.15)
				)
				(justify left bottom)
			)
		)
		(fp_text user "Author: Antmicro"
			(at -1.367 4.905 0)
			(layer "F.Fab")
			(effects
				(font
					(size 0.7 0.7)
					(thickness 0.15)
				)
				(justify left bottom)
			)
		)
		(fp_text user "License: Apache-2.0"
			(at -1.367 6.105 0)
			(layer "F.Fab")
			(effects
				(font
					(size 0.7 0.7)
					(thickness 0.15)
				)
				(justify left bottom)
			)
		)
		(pad "1" smd rect
			(at -1 0.3875)
			(size 0.2 0.475)
			(layers "F.Cu" "F.Mask" "F.Paste")
			(net 203 "/USB/USBA_CC1")
			(pinfunction "CH1")
			(pintype "passive")
			(solder_mask_margin 0.05)
		)
		(pad "2" smd rect
			(at -0.5 0.3875)
			(size 0.2 0.475)
			(layers "F.Cu" "F.Mask" "F.Paste")
			(net 204 "/USB/USBA_CC2")
			(pinfunction "CH2")
			(pintype "passive")
			(solder_mask_margin 0.05)
		)
		(pad "3" smd rect
			(at 0 0.3875)
			(size 0.2 0.475)
			(layers "F.Cu" "F.Mask" "F.Paste")
			(net 3 "GND")
			(pinfunction "GND")
			(pintype "passive")
			(solder_mask_margin 0.05)
		)
		(pad "4" smd rect
			(at 0.5 0.3875)
			(size 0.2 0.475)
			(layers "F.Cu" "F.Mask" "F.Paste")
			(net 205 "/USB/AD_P")
			(pinfunction "CH3")
			(pintype "passive")
			(solder_mask_margin 0.05)
		)
		(pad "5" smd rect
			(at 1 0.3875)
			(size 0.2 0.475)
			(layers "F.Cu" "F.Mask" "F.Paste")
			(net 206 "/USB/AD_N")
			(pinfunction "CH4")
			(pintype "passive")
			(solder_mask_margin 0.05)
		)
		(pad "6" smd rect
			(at 1 -0.3875)
			(size 0.2 0.475)
			(layers "F.Cu" "F.Mask" "F.Paste")
			(net 206 "/USB/AD_N")
			(pinfunction "CH4")
			(pintype "passive")
			(solder_mask_margin 0.05)
		)
		(pad "7" smd rect
			(at 0.5 -0.3875)
			(size 0.2 0.475)
			(layers "F.Cu" "F.Mask" "F.Paste")
			(net 205 "/USB/AD_P")
			(pinfunction "CH3")
			(pintype "passive")
			(solder_mask_margin 0.05)
		)
		(pad "8" smd rect
			(at 0 -0.3875)
			(size 0.2 0.475)
			(layers "F.Cu" "F.Mask" "F.Paste")
			(net 3 "GND")
			(pinfunction "GND")
			(pintype "passive")
			(solder_mask_margin 0.05)
		)
		(pad "9" smd rect
			(at -0.501 -0.3875)
			(size 0.2 0.475)
			(layers "F.Cu" "F.Mask" "F.Paste")
			(net 204 "/USB/USBA_CC2")
			(pinfunction "CH2")
			(pintype "passive")
			(solder_mask_margin 0.05)
		)
		(pad "10" smd rect
			(at -1 -0.3875)
			(size 0.2 0.475)
			(layers "F.Cu" "F.Mask" "F.Paste")
			(net 203 "/USB/USBA_CC1")
			(pinfunction "CH1")
			(pintype "passive")
			(solder_mask_margin 0.05)
		)
	)
	(footprint "antmicro-footprints:SOT-523"
		(layer "B.Cu")
		(at 86.5 120.0895)
		(property "Reference" "Q906"
			(at 1.1 0.9 180)
			(layer "B.SilkS")
			(effects
				(font
					(size 0.7 0.7)
					(thickness 0.15)
				)
				(justify right bottom mirror)
			)
		)
		(property "Value" "PJE138K"
			(at 0.1 -1.824 0)
			(layer "B.Fab")
			(effects
				(font
					(size 0.7 0.7)
					(thickness 0.15)
				)
				(justify right bottom mirror)
			)
		)
		(property "Datasheet" "https://www.mouser.com/datasheet/2/1057/PJE138K-1876698.pdf"
			(at 0 0 0)
			(layer "B.Fab")
			(hide yes)
			(effects
				(font
					(size 1.27 1.27)
					(thickness 0.15)
				)
			)
		)
		(property "MPN" "PJE138K_R1_00001"
			(at 0 0 0)
			(unlocked yes)
			(layer "B.Fab")
			(hide yes)
			(effects
				(font
					(size 1 1)
					(thickness 0.15)
				)
				(justify mirror)
			)
		)
		(property "Manufacturer" "PANJIT"
			(at 0 0 0)
			(unlocked yes)
			(layer "B.Fab")
			(hide yes)
			(effects
				(font
					(size 1 1)
					(thickness 0.15)
				)
				(justify mirror)
			)
		)
		(property "Author" "Antmicro"
			(at 0 0 0)
			(unlocked yes)
			(layer "B.Fab")
			(hide yes)
			(effects
				(font
					(size 1 1)
					(thickness 0.15)
				)
				(justify mirror)
			)
		)
		(property "License" "Apache-2.0"
			(at 0 0 0)
			(unlocked yes)
			(layer "B.Fab")
			(hide yes)
			(effects
				(font
					(size 1 1)
					(thickness 0.15)
				)
				(justify mirror)
			)
		)
		(sheetname "/USB/")
		(sheetfile "usb.kicad_sch")
		(attr smd)
		(fp_line
			(start -0.927 0.051)
			(end -0.927 0.351)
			(stroke
				(width 0.15)
				(type solid)
			)
			(layer "B.SilkS")
		)
		(fp_line
			(start -0.927 0.351)
			(end -0.725 0.551)
			(stroke
				(width 0.15)
				(type solid)
			)
			(layer "B.SilkS")
		)
		(fp_line
			(start -0.725 0.551)
			(end -0.277 0.551)
			(stroke
				(width 0.15)
				(type solid)
			)
			(layer "B.SilkS")
		)
		(fp_line
			(start -0.277 0.551)
			(end -0.277 0.75)
			(stroke
				(width 0.15)
				(type solid)
			)
			(layer "B.SilkS")
		)
		(fp_circle
			(center -0.9652 -0.9652)
			(end -0.9152 -0.9652)
			(stroke
				(width 0.15)
				(type solid)
			)
			(fill yes)
			(layer "B.SilkS")
		)
		(fp_line
			(start -1.12 -1.15)
			(end 1.1 -1.15)
			(stroke
				(width 0.05)
				(type solid)
			)
			(layer "B.CrtYd")
		)
		(fp_line
			(start -1.12 1.16)
			(end -1.12 -1.15)
			(stroke
				(width 0.05)
				(type solid)
			)
			(layer "B.CrtYd")
		)
		(fp_line
			(start -1.12 1.16)
			(end 1.1 1.16)
			(stroke
				(width 0.05)
				(type solid)
			)
			(layer "B.CrtYd")
		)
		(fp_line
			(start 1.1 1.16)
			(end 1.1 -1.15)
			(stroke
				(width 0.05)
				(type solid)
			)
			(layer "B.CrtYd")
		)
		(fp_line
			(start -0.802 0.276)
			(end -0.802 -0.424)
			(stroke
				(width 0.15)
				(type solid)
			)
			(layer "B.Fab")
		)
		(fp_line
			(start -0.652 0.425)
			(end -0.802 0.276)
			(stroke
				(width 0.15)
				(type solid)
			)
			(layer "B.Fab")
		)
		(fp_line
			(start 0.8 -0.424)
			(end -0.802 -0.424)
			(stroke
				(width 0.15)
				(type solid)
			)
			(layer "B.Fab")
		)
		(fp_line
			(start 0.8 0.425)
			(end -0.652 0.425)
			(stroke
				(width 0.15)
				(type solid)
			)
			(layer "B.Fab")
		)
		(fp_line
			(start 0.8 0.425)
			(end 0.8 -0.424)
			(stroke
				(width 0.15)
				(type solid)
			)
			(layer "B.Fab")
		)
		(fp_circle
			(center -0.9652 -0.9652)
			(end -0.9144 -0.9652)
			(stroke
				(width 0.15)
				(type solid)
			)
			(fill no)
			(layer "B.Fab")
		)
		(fp_text user "Author: Antmicro"
			(at -1.12 -6.224 180)
			(layer "B.Fab")
			(effects
				(font
					(size 0.7 0.7)
					(thickness 0.15)
				)
				(justify left bottom mirror)
			)
		)
		(fp_text user "${REFERENCE}"
			(at -1.12 -3.824 180)
			(layer "B.Fab")
			(effects
				(font
					(size 0.7 0.7)
					(thickness 0.15)
				)
				(justify left bottom mirror)
			)
		)
		(fp_text user "License: Apache-2.0"
			(at -1.12 -5.024 180)
			(layer "B.Fab")
			(effects
				(font
					(size 0.7 0.7)
					(thickness 0.15)
				)
				(justify left bottom mirror)
			)
		)
		(pad "1" smd rect
			(at -0.5 -0.65)
			(size 0.4 0.51)
			(layers "B.Cu" "B.Mask" "B.Paste")
			(net 499 "Net-(Q906-G)")
			(pinfunction "G")
			(pintype "input")
		)
		(pad "2" smd rect
			(at 0.498 -0.65)
			(size 0.4 0.51)
			(layers "B.Cu" "B.Mask" "B.Paste")
			(net 3 "GND")
			(pinfunction "S")
			(pintype "passive")
		)
		(pad "3" smd rect
			(at 0 0.652)
			(size 0.4 0.51)
			(layers "B.Cu" "B.Mask" "B.Paste")
			(net 498 "Net-(D906-C)")
			(pinfunction "D")
			(pintype "passive")
		)
	)
)
